# BASEBOARD_FAB2 (Tioga Pass) — schematic netlist excerpt (pin names and nets, part order shuffled) for the footprints in the layout excerpt that follows; sources: Cadence DE-HDL packaged netlist, KiCad conversion of Wiwynn_Tioga_Pass_MB.brd

RT29  1R3F-GP  1%  pkg RCL_GP  page 219 : \1\ = VR_PVDDQ_DEF_PH1_SW_RC ; \2\ = GND
R5D6  RES  10.0 1% EMPTY  pkg 0402  page 37 : A = PVCCIO_CPU0 ; B = VSENSE_PMAX_CPU0
R7W15  RES  0.0 5% CHIP  pkg 0402  page 119 : A = FM_OCP_MEZZA_PRES ; B = FM_OCP_MEZZA_PRES_R

(kicad_pcb
	(version 20260206)
	(generator "pcbnew")
	(generator_version "10.0")
	(general
		(thickness 1.6)
		(legacy_teardrops no)
	)
	(paper "A4")
	(title_block
		(title "Wiwynn_Tioga_Pass_MB.brd")
		(comment 1 "Tioga Pass / footprints 150-152 of 4770")
	)
	(layers
		(0 "F.Cu" signal "TOP")
		(4 "In1.Cu" signal "L2GND")
		(6 "In2.Cu" signal "L3")
		(8 "In3.Cu" signal "L4GND")
		(10 "In4.Cu" signal "L5")
		(12 "In5.Cu" signal "L6GND")
		(14 "In6.Cu" signal "L7VCC")
		(16 "In7.Cu" signal "L8VCC")
		(18 "In8.Cu" signal "L9GND")
		(20 "In9.Cu" signal "L10")
		(22 "In10.Cu" signal "L11GND")
		(24 "In11.Cu" signal "L12")
		(26 "In12.Cu" signal "L13GND")
		(2 "B.Cu" signal "BOTTOM")
		(9 "F.Adhes" user "F.Adhesive")
		(11 "B.Adhes" user "B.Adhesive")
		(13 "F.Paste" user "Package Geometry/Pastemask Top")
		(15 "B.Paste" user "Package Geometry/Pastemask Bottom")
		(5 "F.SilkS" user "Ref Des/Silkscreen Top")
		(7 "B.SilkS" user "Ref Des/Silkscreen Bottom")
		(1 "F.Mask" user "Board Geometry/Soldermask Top")
		(3 "B.Mask" user "Board Geometry/Soldermask Bottom")
		(17 "Dwgs.User" user "User.Drawings")
		(19 "Cmts.User" user "User.Comments")
		(21 "Eco1.User" user "User.Eco1")
		(23 "Eco2.User" user "User.Eco2")
		(25 "Edge.Cuts" user "Board Geometry/Outline")
		(27 "Margin" user)
		(31 "F.CrtYd" user "Package Geometry/Place Bound Top")
		(29 "B.CrtYd" user "Package Geometry/Place Bound Bottom")
		(35 "F.Fab" user "Ref Des/Assembly Top")
		(33 "B.Fab" user "Ref Des/Assembly Bottom")
	)
	(footprint ""
		(layer "F.Cu")
		(at 385.30784 -89.55532 180)
		(property "Reference" "R7W15"
			(at -0.8382 -0.67818 180)
			(unlocked yes)
			(layer "F.SilkS")
			(effects
				(font
					(size 0.4064 0.254)
					(thickness 0.1524)
				)
				(justify left)
			)
		)
		(property "Value" ""
			(at 0 0 180)
			(layer "F.Fab")
			(effects
				(font
					(size 1.27 1.27)
				)
			)
		)
		(duplicate_pad_numbers_are_jumpers no)
		(fp_poly
			(pts
				(xy -0.2794 -0.1016) (xy 0.2794 -0.1016) (xy 0.2794 0.9906) (xy -0.2794 0.9906)
			)
			(stroke
				(width 0)
				(type default)
			)
			(fill no)
			(layer "F.CrtYd")
		)
		(fp_line
			(start 0.2794 0.9906)
			(end 0.2794 -0.1016)
			(stroke
				(width 0.1)
				(type default)
			)
			(layer "F.Fab")
		)
		(fp_line
			(start 0.2794 -0.1016)
			(end -0.2794 -0.1016)
			(stroke
				(width 0.1)
				(type default)
			)
			(layer "F.Fab")
		)
		(fp_line
			(start -0.2794 0.9906)
			(end 0.2794 0.9906)
			(stroke
				(width 0.1)
				(type default)
			)
			(layer "F.Fab")
		)
		(fp_line
			(start -0.2794 -0.1016)
			(end -0.2794 0.9906)
			(stroke
				(width 0.1)
				(type default)
			)
			(layer "F.Fab")
		)
		(pad "1" smd rect
			(at 0 0 180)
			(size 0.508 0.508)
			(layers "F.Cu" "F.Mask" "F.Paste")
			(net "FM_OCP_MEZZA_PRES")
		)
		(pad "2" smd rect
			(at 0 0.889 180)
			(size 0.508 0.508)
			(layers "F.Cu" "F.Mask" "F.Paste")
			(net "FM_OCP_MEZZA_PRES_R")
		)
		(zone
			(layer "F.Cu")
			(hatch none 0.5)
			(connect_pads
				(clearance 0)
			)
			(min_thickness 0.25)
			(keepout
				(tracks not_allowed)
				(vias allowed)
				(pads allowed)
				(copperpour not_allowed)
				(footprints allowed)
			)
			(placement
				(enabled no)
				(sheetname "")
			)
			(fill
				(thermal_gap 0.5)
				(thermal_bridge_width 0.5)
				(island_removal_mode 0)
			)
			(polygon
				(pts
					(xy 385.56184 -90.19032) (xy 385.05384 -90.19032) (xy 385.05384 -89.80932) (xy 385.56184 -89.80932)
				)
			)
		)
		(zone
			(layer "F.Cu")
			(hatch none 0.5)
			(connect_pads
				(clearance 0)
			)
			(min_thickness 0.25)
			(keepout
				(tracks allowed)
				(vias not_allowed)
				(pads allowed)
				(copperpour not_allowed)
				(footprints allowed)
			)
			(placement
				(enabled no)
				(sheetname "")
			)
			(fill
				(thermal_gap 0.5)
				(thermal_bridge_width 0.5)
				(island_removal_mode 0)
			)
			(polygon
				(pts
					(xy 385.56184 -89.80932) (xy 385.05384 -89.80932) (xy 385.05384 -90.19032) (xy 385.56184 -90.19032)
				)
			)
		)
	)
	(footprint ""
		(layer "F.Cu")
		(at 345.359228 -157.1244 90)
		(property "Reference" "RT29"
			(at 0 0 90)
			(layer "F.SilkS")
			(hide yes)
			(effects
				(font
					(size 1.27 1.27)
				)
			)
		)
		(property "Value" "*"
			(at -0.0254 -2.6289 90)
			(unlocked yes)
			(layer "F.Fab")
			(hide yes)
			(effects
				(font
					(size 1.27 1.016)
					(thickness 0.1524)
				)
			)
		)
		(property "Device Type" "1R3F-GP_RCL_GP-1R3F-GP,64.1R00A"
			(at -0.0254 -4.1529 90)
			(unlocked yes)
			(layer "F.Fab")
			(hide yes)
			(effects
				(font
					(size 1.27 1.016)
					(thickness 0.1524)
				)
			)
		)
		(duplicate_pad_numbers_are_jumpers no)
		(fp_line
			(start 0.2032 0)
			(end 0.4826 0)
			(stroke
				(width 0.2032)
				(type default)
			)
			(layer "F.SilkS")
		)
		(fp_line
			(start -0.4826 0)
			(end -0.2032 0)
			(stroke
				(width 0.2032)
				(type default)
			)
			(layer "F.SilkS")
		)
		(fp_rect
			(start -0.5842 1.3335)
			(end 0.5842 -1.3335)
			(stroke
				(width 0)
				(type default)
			)
			(fill no)
			(layer "F.CrtYd")
		)
		(fp_rect
			(start -0.5842 1.3335)
			(end 0.5842 -1.3335)
			(stroke
				(width 0)
				(type default)
			)
			(fill no)
			(layer "F.Fab")
		)
		(pad "1" smd custom
			(at 0 -0.762 90)
			(size 0.2159 0.2159)
			(layers "F.Cu" "F.Mask" "F.Paste")
			(net "VR_PVDDQ_DEF_PH1_SW_RC")
			(options
				(clearance outline)
				(anchor circle)
			)
			(primitives
				(gr_poly
					(pts
						(arc
							(start -0.3302 -0.4318)
							(mid -0.402042 -0.402042)
							(end -0.4318 -0.3302)
						)
						(arc
							(start -0.4318 0.3302)
							(mid -0.402042 0.402042)
							(end -0.3302 0.4318)
						)
						(arc
							(start 0.3302 0.4318)
							(mid 0.402042 0.402042)
							(end 0.4318 0.3302)
						)
						(arc
							(start 0.4318 -0.3302)
							(mid 0.402042 -0.402042)
							(end 0.3302 -0.4318)
						)
					)
					(width 0)
					(fill yes)
				)
			)
		)
		(pad "2" smd custom
			(at 0 0.762 90)
			(size 0.2159 0.2159)
			(layers "F.Cu" "F.Mask" "F.Paste")
			(net "GND")
			(options
				(clearance outline)
				(anchor circle)
			)
			(primitives
				(gr_poly
					(pts
						(arc
							(start -0.3302 -0.4318)
							(mid -0.402042 -0.402042)
							(end -0.4318 -0.3302)
						)
						(arc
							(start -0.4318 0.3302)
							(mid -0.402042 0.402042)
							(end -0.3302 0.4318)
						)
						(arc
							(start 0.3302 0.4318)
							(mid 0.402042 0.402042)
							(end 0.4318 0.3302)
						)
						(arc
							(start 0.4318 -0.3302)
							(mid 0.402042 -0.402042)
							(end 0.3302 -0.4318)
						)
					)
					(width 0)
					(fill yes)
				)
			)
		)
	)
	(footprint ""
		(layer "F.Cu")
		(at 273.558 -69.977)
		(property "Reference" "R5D6"
			(at 0 0 0)
			(layer "F.SilkS")
			(hide yes)
			(effects
				(font
					(size 1.27 1.27)
				)
			)
		)
		(property "Value" ""
			(at 0 0 0)
			(layer "F.Fab")
			(effects
				(font
					(size 1.27 1.27)
				)
			)
		)
		(duplicate_pad_numbers_are_jumpers no)
		(fp_poly
			(pts
				(xy -0.2794 -0.1016) (xy 0.2794 -0.1016) (xy 0.2794 0.9906) (xy -0.2794 0.9906)
			)
			(stroke
				(width 0)
				(type default)
			)
			(fill no)
			(layer "F.CrtYd")
		)
		(fp_line
			(start -0.2794 -0.1016)
			(end -0.2794 0.9906)
			(stroke
				(width 0.1)
				(type default)
			)
			(layer "F.Fab")
		)
		(fp_line
			(start -0.2794 0.9906)
			(end 0.2794 0.9906)
			(stroke
				(width 0.1)
				(type default)
			)
			(layer "F.Fab")
		)
		(fp_line
			(start 0.2794 -0.1016)
			(end -0.2794 -0.1016)
			(stroke
				(width 0.1)
				(type default)
			)
			(layer "F.Fab")
		)
		(fp_line
			(start 0.2794 0.9906)
			(end 0.2794 -0.1016)
			(stroke
				(width 0.1)
				(type default)
			)
			(layer "F.Fab")
		)
		(pad "1" smd rect
			(at 0 0)
			(size 0.508 0.508)
			(layers "F.Cu" "F.Mask" "F.Paste")
			(net "PVCCIO_CPU0")
		)
		(pad "2" smd rect
			(at 0 0.889)
			(size 0.508 0.508)
			(layers "F.Cu" "F.Mask" "F.Paste")
			(net "VSENSE_PMAX_CPU0")
		)
		(zone
			(layer "F.Cu")
			(hatch none 0.5)
			(connect_pads
				(clearance 0)
			)
			(min_thickness 0.25)
			(keepout
				(tracks allowed)
				(vias not_allowed)
				(pads allowed)
				(copperpour not_allowed)
				(footprints allowed)
			)
			(placement
				(enabled no)
				(sheetname "")
			)
			(fill
				(thermal_gap 0.5)
				(thermal_bridge_width 0.5)
				(island_removal_mode 0)
			)
			(polygon
				(pts
					(xy 273.304 -69.723) (xy 273.812 -69.723) (xy 273.812 -69.342) (xy 273.304 -69.342)
				)
			)
		)
		(zone
			(layer "F.Cu")
			(hatch none 0.5)
			(connect_pads
				(clearance 0)
			)
			(min_thickness 0.25)
			(keepout
				(tracks not_allowed)
				(vias allowed)
				(pads allowed)
				(copperpour not_allowed)
				(footprints allowed)
			)
			(placement
				(enabled no)
				(sheetname "")
			)
			(fill
				(thermal_gap 0.5)
				(thermal_bridge_width 0.5)
				(island_removal_mode 0)
			)
			(polygon
				(pts
					(xy 273.304 -69.342) (xy 273.812 -69.342) (xy 273.812 -69.723) (xy 273.304 -69.723)
				)
			)
		)
	)
)
